# T6G (Grand Teton) — schematic netlist excerpt (pin names and nets, part order shuffled) for the footprints in the layout excerpt that follows; sources: Cadence DE-HDL packaged netlist, KiCad conversion of 04192023_DAF0TMB3IC0_F0TG_MB_C_brd_V02_OCP.brd

R1252  Q_RES  0 5% CHIP  pkg 0402LF  page 258 : A = P1V8_CPU0_RT_1D_ADC ; B = P1V8_CPU0_RT_1D_ADC_TIC

(kicad_pcb
	(version 20260206)
	(generator "pcbnew")
	(generator_version "10.0")
	(general
		(thickness 1.6)
		(legacy_teardrops no)
	)
	(paper "A4")
	(title_block
		(title "04192023_DAF0TMB3IC0_F0TG_MB_C_brd_V02_OCP.brd")
		(comment 1 "Grand Teton / footprints 6865-6865 of 8354")
	)
	(layers
		(0 "F.Cu" signal "TOP")
		(4 "In1.Cu" signal "GND")
		(6 "In2.Cu" signal "IN1")
		(8 "In3.Cu" signal "GND1")
		(10 "In4.Cu" signal "IN2")
		(12 "In5.Cu" signal "GND2")
		(14 "In6.Cu" signal "IN3")
		(16 "In7.Cu" signal "GND3")
		(18 "In8.Cu" signal "VCC")
		(20 "In9.Cu" signal "VCC1")
		(22 "In10.Cu" signal "GND4")
		(24 "In11.Cu" signal "IN4")
		(26 "In12.Cu" signal "GND5")
		(28 "In13.Cu" signal "IN5")
		(30 "In14.Cu" signal "GND6")
		(32 "In15.Cu" signal "IN6")
		(34 "In16.Cu" signal "GND7")
		(2 "B.Cu" signal "BOTTOM")
		(9 "F.Adhes" user "F.Adhesive")
		(11 "B.Adhes" user "B.Adhesive")
		(13 "F.Paste" user "Package Geometry/Pastemask Top")
		(15 "B.Paste" user "Package Geometry/Pastemask Bottom")
		(5 "F.SilkS" user "Ref Des/Silkscreen Top")
		(7 "B.SilkS" user "Ref Des/Silkscreen Bottom")
		(1 "F.Mask" user "Board Geometry/Soldermask Top")
		(3 "B.Mask" user "Board Geometry/Soldermask Bottom")
		(17 "Dwgs.User" user "User.Drawings")
		(19 "Cmts.User" user "User.Comments")
		(21 "Eco1.User" user "User.Eco1")
		(23 "Eco2.User" user "User.Eco2")
		(25 "Edge.Cuts" user "Board Geometry/Outline")
		(27 "Margin" user)
		(31 "F.CrtYd" user "Package Geometry/Place Bound Top")
		(29 "B.CrtYd" user "Package Geometry/Place Bound Bottom")
		(35 "F.Fab" user "Ref Des/Assembly Top")
		(33 "B.Fab" user "Ref Des/Assembly Bottom")
	)
	(footprint ""
		(layer "B.Cu")
		(at 231.082596 -324.980554)
		(property "Reference" "R1252"
			(at 0 0 0)
			(layer "B.SilkS")
			(hide yes)
			(effects
				(font
					(size 1.27 1.27)
				)
				(justify mirror)
			)
		)
		(property "Value" ""
			(at 0 0 0)
			(layer "B.Fab")
			(effects
				(font
					(size 1.27 1.27)
				)
				(justify mirror)
			)
		)
		(duplicate_pad_numbers_are_jumpers no)
		(fp_line
			(start -0.7874 -0.4064)
			(end -0.7874 0.4064)
			(stroke
				(width 0.1524)
				(type default)
			)
			(layer "B.SilkS")
		)
		(fp_line
			(start -0.7874 0.4064)
			(end 0.7874 0.4064)
			(stroke
				(width 0.1524)
				(type default)
			)
			(layer "B.SilkS")
		)
		(fp_line
			(start 0.7874 -0.4064)
			(end -0.7874 -0.4064)
			(stroke
				(width 0.1524)
				(type default)
			)
			(layer "B.SilkS")
		)
		(fp_line
			(start 0.7874 0.4064)
			(end 0.7874 -0.4064)
			(stroke
				(width 0.1524)
				(type default)
			)
			(layer "B.SilkS")
		)
		(fp_line
			(start -0.67945 -0.3048)
			(end -0.67945 0.3048)
			(stroke
				(width 0.1)
				(type default)
			)
			(layer "B.Fab")
		)
		(fp_line
			(start -0.67945 0.3048)
			(end -0.120396 0.3048)
			(stroke
				(width 0.1)
				(type default)
			)
			(layer "B.Fab")
		)
		(fp_line
			(start -0.12065 -0.3048)
			(end -0.67945 -0.3048)
			(stroke
				(width 0.1)
				(type default)
			)
			(layer "B.Fab")
		)
		(fp_line
			(start -0.12065 -0.2794)
			(end -0.12065 -0.3048)
			(stroke
				(width 0.1)
				(type default)
			)
			(layer "B.Fab")
		)
		(fp_line
			(start -0.120396 0.2794)
			(end 0.12065 0.2794)
			(stroke
				(width 0.1)
				(type default)
			)
			(layer "B.Fab")
		)
		(fp_line
			(start -0.120396 0.3048)
			(end -0.120396 0.2794)
			(stroke
				(width 0.1)
				(type default)
			)
			(layer "B.Fab")
		)
		(fp_line
			(start 0.12065 -0.305054)
			(end 0.12065 -0.2794)
			(stroke
				(width 0.1)
				(type default)
			)
			(layer "B.Fab")
		)
		(fp_line
			(start 0.12065 -0.2794)
			(end -0.12065 -0.2794)
			(stroke
				(width 0.1)
				(type default)
			)
			(layer "B.Fab")
		)
		(fp_line
			(start 0.12065 0.2794)
			(end 0.12065 0.3048)
			(stroke
				(width 0.1)
				(type default)
			)
			(layer "B.Fab")
		)
		(fp_line
			(start 0.12065 0.3048)
			(end 0.67945 0.3048)
			(stroke
				(width 0.1)
				(type default)
			)
			(layer "B.Fab")
		)
		(fp_line
			(start 0.67945 -0.305054)
			(end 0.12065 -0.305054)
			(stroke
				(width 0.1)
				(type default)
			)
			(layer "B.Fab")
		)
		(fp_line
			(start 0.67945 0.3048)
			(end 0.67945 -0.305054)
			(stroke
				(width 0.1)
				(type default)
			)
			(layer "B.Fab")
		)
		(pad "1" smd rect
			(at 0.40005 0)
			(size 0.4572 0.508)
			(layers "B.Cu" "B.Mask" "B.Paste")
			(net "P1V8_CPU0_RT_1D_ADC")
		)
		(pad "2" smd rect
			(at -0.40005 0)
			(size 0.4572 0.508)
			(layers "B.Cu" "B.Mask" "B.Paste")
			(net "P1V8_CPU0_RT_1D_ADC_TIC")
		)
	)
)
